# BASEBOARD_FAB2 (Tioga Pass) — schematic netlist excerpt (pin names and nets, part order shuffled) for the footprints in the layout excerpt that follows; sources: Cadence DE-HDL packaged netlist, KiCad conversion of Wiwynn_Tioga_Pass_MB.brd

EU1G2  PXM1310B  IC  pkg QFN  page 223
  BPWM1  = NC
  DNC(0)  = NC
  APWM3  = NC
  APWM2  = VR_PVDDQ_GHJ_PWM2
  APWM1  = VR_PVDDQ_GHJ_PWM1
  SDA  = SMB_VR_STBY_LVC3_SDA
  SCL  = SMB_VR_STBY_LVC3_SCL
  RESET_N  = NC
  AVRRDY  = PWRGD_PVDDQ_GHJ_R
  AVREN  = VR_PVDDQ_GHJ_VREN
  VRHOT_N  = IRQ_PVDDQ_GHJ_VRHOT_LVT3_R_N
  PINALRT_N  = NC
  MP0  = PU_VR_PVDDQ_GHJ_FAULT1
  MP1  = TP_PVDDQ_GHJ_MP1
  VCLK  = SVID_CLK_PVDDQ_GHJ
  VDIO  = SVID_VDIO_PVDDQ_GHJ
  VALRT_N  = SVID_ALERT_PVDDQ_GHJ
  MP2  = TP_PVDDQ_GHJ_MP2
  AVSEN  = VR_PVDDQ_GHJ_AVSP
  AVREF  = VSENSE_PVDDQ_GHJ_N
  AIREF1  = VR_PVDDQ_GHJ_AIREF1
  AISEN1  = ISENSE_PVDDQ_GHJ_PH1_IMON
  AIREF2  = VR_PVDDQ_GHJ_AIREF2
  AISEN2  = ISENSE_PVDDQ_GHJ_PH2_IMON
  AIREF3  = NC
  AISEN3  = NC
  GND  = GND
  DNC(1)  = NC
  BVSEN  = NC
  BVREF  = NC
  BIREF1  = NC
  BISEN1  = GND
  XADDR2  = VR_PVDDQ_GHJ_XADDR2
  BTSEN  = NC
  ATSEN  = A_TSENSE_PVDDQ_GHJ
  XADDR1  = VR_PVDDQ_GHJ_XADDR1
  VINSEN  = VR_PVDDQ_GHJ_VINSEN
  IINSEN  = VR_PVDDQ_GHJ_AIINSEN
  VDD  = VR_PVDDQ_GHJ_VDD
  VD12  = VR_PVDDQ_GHJ_VD12
  THPAD  = GND

(kicad_pcb
	(version 20260206)
	(generator "pcbnew")
	(generator_version "10.0")
	(general
		(thickness 1.6)
		(legacy_teardrops no)
	)
	(paper "A4")
	(title_block
		(title "Wiwynn_Tioga_Pass_MB.brd")
		(comment 1 "Tioga Pass / footprint 2178 of 4770 (EU1G2), pads 18-34 of 41")
	)
	(layers
		(0 "F.Cu" signal "TOP")
		(4 "In1.Cu" signal "L2GND")
		(6 "In2.Cu" signal "L3")
		(8 "In3.Cu" signal "L4GND")
		(10 "In4.Cu" signal "L5")
		(12 "In5.Cu" signal "L6GND")
		(14 "In6.Cu" signal "L7VCC")
		(16 "In7.Cu" signal "L8VCC")
		(18 "In8.Cu" signal "L9GND")
		(20 "In9.Cu" signal "L10")
		(22 "In10.Cu" signal "L11GND")
		(24 "In11.Cu" signal "L12")
		(26 "In12.Cu" signal "L13GND")
		(2 "B.Cu" signal "BOTTOM")
		(9 "F.Adhes" user "F.Adhesive")
		(11 "B.Adhes" user "B.Adhesive")
		(13 "F.Paste" user "Package Geometry/Pastemask Top")
		(15 "B.Paste" user "Package Geometry/Pastemask Bottom")
		(5 "F.SilkS" user "Ref Des/Silkscreen Top")
		(7 "B.SilkS" user "Ref Des/Silkscreen Bottom")
		(1 "F.Mask" user "Board Geometry/Soldermask Top")
		(3 "B.Mask" user "Board Geometry/Soldermask Bottom")
		(17 "Dwgs.User" user "User.Drawings")
		(19 "Cmts.User" user "User.Comments")
		(21 "Eco1.User" user "User.Eco1")
		(23 "Eco2.User" user "User.Eco2")
		(25 "Edge.Cuts" user "Board Geometry/Outline")
		(27 "Margin" user)
		(31 "F.CrtYd" user "Package Geometry/Place Bound Top")
		(29 "B.CrtYd" user "Package Geometry/Place Bound Bottom")
		(35 "F.Fab" user "Ref Des/Assembly Top")
		(33 "B.Fab" user "Ref Des/Assembly Bottom")
	)
	(footprint ""
		(layer "F.Cu")
		(at 10.033 0.24765 180)
		(property "Reference" "EU1G2"
			(at 2.4638 -3.53187 0)
			(unlocked yes)
			(layer "F.SilkS")
			(effects
				(font
					(size 0.7874 0.5842)
					(thickness 0.1524)
				)
				(justify left)
			)
		)
		(property "Value" ""
			(at 0 0 180)
			(layer "F.Fab")
			(effects
				(font
					(size 1.27 1.27)
				)
			)
		)
		(duplicate_pad_numbers_are_jumpers no)
		(pad "18" smd custom
			(at 0.999998 2.4511 180)
			(size 0.0508 0.0508)
			(layers "F.Cu" "F.Mask" "F.Paste")
			(net "TP_PVDDQ_GHJ_MP2")
			(options
				(clearance outline)
				(anchor circle)
			)
			(primitives
				(gr_poly
					(pts
						(arc
							(start -0.1016 -0.254)
							(mid 0 -0.3556)
							(end 0.1016 -0.254)
						)
						(xy 0.1016 0.3556) (xy -0.1016 0.3556)
					)
					(width 0)
					(fill yes)
				)
			)
		)
		(pad "19" smd custom
			(at 1.400048 2.4511 180)
			(size 0.0508 0.0508)
			(layers "F.Cu" "F.Mask" "F.Paste")
			(net "VR_PVDDQ_GHJ_AVSP")
			(options
				(clearance outline)
				(anchor circle)
			)
			(primitives
				(gr_poly
					(pts
						(arc
							(start -0.1016 -0.254)
							(mid 0 -0.3556)
							(end 0.1016 -0.254)
						)
						(xy 0.1016 0.3556) (xy -0.1016 0.3556)
					)
					(width 0)
					(fill yes)
				)
			)
		)
		(pad "20" smd custom
			(at 1.800098 2.4511 180)
			(size 0.0508 0.0508)
			(layers "F.Cu" "F.Mask" "F.Paste")
			(net "VSENSE_PVDDQ_GHJ_N")
			(options
				(clearance outline)
				(anchor circle)
			)
			(primitives
				(gr_poly
					(pts
						(arc
							(start -0.1016 -0.254)
							(mid 0 -0.3556)
							(end 0.1016 -0.254)
						)
						(xy 0.1016 0.3556) (xy -0.1016 0.3556)
					)
					(width 0)
					(fill yes)
				)
			)
		)
		(pad "21" smd custom
			(at 2.4511 1.800098 180)
			(size 0.0508 0.0508)
			(layers "F.Cu" "F.Mask" "F.Paste")
			(net "VR_PVDDQ_GHJ_AIREF1")
			(options
				(clearance outline)
				(anchor circle)
			)
			(primitives
				(gr_poly
					(pts
						(arc
							(start -0.254 0.1016)
							(mid -0.3556 0)
							(end -0.254 -0.1016)
						)
						(xy 0.3556 -0.1016) (xy 0.3556 0.1016)
					)
					(width 0)
					(fill yes)
				)
			)
		)
		(pad "22" smd custom
			(at 2.4511 1.400048 180)
			(size 0.0508 0.0508)
			(layers "F.Cu" "F.Mask" "F.Paste")
			(net "ISENSE_PVDDQ_GHJ_PH1_IMON")
			(options
				(clearance outline)
				(anchor circle)
			)
			(primitives
				(gr_poly
					(pts
						(arc
							(start -0.254 0.1016)
							(mid -0.3556 0)
							(end -0.254 -0.1016)
						)
						(xy 0.3556 -0.1016) (xy 0.3556 0.1016)
					)
					(width 0)
					(fill yes)
				)
			)
		)
		(pad "23" smd custom
			(at 2.4511 0.999998 180)
			(size 0.0508 0.0508)
			(layers "F.Cu" "F.Mask" "F.Paste")
			(net "VR_PVDDQ_GHJ_AIREF2")
			(options
				(clearance outline)
				(anchor circle)
			)
			(primitives
				(gr_poly
					(pts
						(arc
							(start -0.254 0.1016)
							(mid -0.3556 0)
							(end -0.254 -0.1016)
						)
						(xy 0.3556 -0.1016) (xy 0.3556 0.1016)
					)
					(width 0)
					(fill yes)
				)
			)
		)
		(pad "24" smd custom
			(at 2.4511 0.599948 180)
			(size 0.0508 0.0508)
			(layers "F.Cu" "F.Mask" "F.Paste")
			(net "ISENSE_PVDDQ_GHJ_PH2_IMON")
			(options
				(clearance outline)
				(anchor circle)
			)
			(primitives
				(gr_poly
					(pts
						(arc
							(start -0.254 0.1016)
							(mid -0.3556 0)
							(end -0.254 -0.1016)
						)
						(xy 0.3556 -0.1016) (xy 0.3556 0.1016)
					)
					(width 0)
					(fill yes)
				)
			)
		)
		(pad "25" smd custom
			(at 2.4511 0.199898 180)
			(size 0.0508 0.0508)
			(layers "F.Cu" "F.Mask" "F.Paste")
			(net "Net_247")
			(options
				(clearance outline)
				(anchor circle)
			)
			(primitives
				(gr_poly
					(pts
						(arc
							(start -0.254 0.1016)
							(mid -0.3556 0)
							(end -0.254 -0.1016)
						)
						(xy 0.3556 -0.1016) (xy 0.3556 0.1016)
					)
					(width 0)
					(fill yes)
				)
			)
		)
		(pad "26" smd custom
			(at 2.4511 -0.199898 180)
			(size 0.0508 0.0508)
			(layers "F.Cu" "F.Mask" "F.Paste")
			(net "Net_246")
			(options
				(clearance outline)
				(anchor circle)
			)
			(primitives
				(gr_poly
					(pts
						(arc
							(start -0.254 0.1016)
							(mid -0.3556 0)
							(end -0.254 -0.1016)
						)
						(xy 0.3556 -0.1016) (xy 0.3556 0.1016)
					)
					(width 0)
					(fill yes)
				)
			)
		)
		(pad "27" smd custom
			(at 2.4511 -0.599948 180)
			(size 0.0508 0.0508)
			(layers "F.Cu" "F.Mask" "F.Paste")
			(net "GND")
			(options
				(clearance outline)
				(anchor circle)
			)
			(primitives
				(gr_poly
					(pts
						(arc
							(start -0.254 0.1016)
							(mid -0.3556 0)
							(end -0.254 -0.1016)
						)
						(xy 0.3556 -0.1016) (xy 0.3556 0.1016)
					)
					(width 0)
					(fill yes)
				)
			)
		)
		(pad "28" smd custom
			(at 2.4511 -0.999998 180)
			(size 0.0508 0.0508)
			(layers "F.Cu" "F.Mask" "F.Paste")
			(net "Net_350")
			(options
				(clearance outline)
				(anchor circle)
			)
			(primitives
				(gr_poly
					(pts
						(arc
							(start -0.254 0.1016)
							(mid -0.3556 0)
							(end -0.254 -0.1016)
						)
						(xy 0.3556 -0.1016) (xy 0.3556 0.1016)
					)
					(width 0)
					(fill yes)
				)
			)
		)
		(pad "29" smd custom
			(at 2.4511 -1.400048 180)
			(size 0.0508 0.0508)
			(layers "F.Cu" "F.Mask" "F.Paste")
			(net "Net_234")
			(options
				(clearance outline)
				(anchor circle)
			)
			(primitives
				(gr_poly
					(pts
						(arc
							(start -0.254 0.1016)
							(mid -0.3556 0)
							(end -0.254 -0.1016)
						)
						(xy 0.3556 -0.1016) (xy 0.3556 0.1016)
					)
					(width 0)
					(fill yes)
				)
			)
		)
		(pad "30" smd custom
			(at 2.4511 -1.800098 180)
			(size 0.0508 0.0508)
			(layers "F.Cu" "F.Mask" "F.Paste")
			(net "Net_233")
			(options
				(clearance outline)
				(anchor circle)
			)
			(primitives
				(gr_poly
					(pts
						(arc
							(start -0.254 0.1016)
							(mid -0.3556 0)
							(end -0.254 -0.1016)
						)
						(xy 0.3556 -0.1016) (xy 0.3556 0.1016)
					)
					(width 0)
					(fill yes)
				)
			)
		)
		(pad "31" smd custom
			(at 1.800098 -2.4511 180)
			(size 0.0508 0.0508)
			(layers "F.Cu" "F.Mask" "F.Paste")
			(net "Net_231")
			(options
				(clearance outline)
				(anchor circle)
			)
			(primitives
				(gr_poly
					(pts
						(arc
							(start 0.1016 0.254)
							(mid 0 0.3556)
							(end -0.1016 0.254)
						)
						(xy -0.1016 -0.3556) (xy 0.1016 -0.3556)
					)
					(width 0)
					(fill yes)
				)
			)
		)
		(pad "32" smd custom
			(at 1.400048 -2.4511 180)
			(size 0.0508 0.0508)
			(layers "F.Cu" "F.Mask" "F.Paste")
			(net "GND")
			(options
				(clearance outline)
				(anchor circle)
			)
			(primitives
				(gr_poly
					(pts
						(arc
							(start 0.1016 0.254)
							(mid 0 0.3556)
							(end -0.1016 0.254)
						)
						(xy -0.1016 -0.3556) (xy 0.1016 -0.3556)
					)
					(width 0)
					(fill yes)
				)
			)
		)
		(pad "33" smd custom
			(at 0.999998 -2.4511 180)
			(size 0.0508 0.0508)
			(layers "F.Cu" "F.Mask" "F.Paste")
			(net "VR_PVDDQ_GHJ_XADDR2")
			(options
				(clearance outline)
				(anchor circle)
			)
			(primitives
				(gr_poly
					(pts
						(arc
							(start 0.1016 0.254)
							(mid 0 0.3556)
							(end -0.1016 0.254)
						)
						(xy -0.1016 -0.3556) (xy 0.1016 -0.3556)
					)
					(width 0)
					(fill yes)
				)
			)
		)
		(pad "34" smd custom
			(at 0.599948 -2.4511 180)
			(size 0.0508 0.0508)
			(layers "F.Cu" "F.Mask" "F.Paste")
			(net "Net_232")
			(options
				(clearance outline)
				(anchor circle)
			)
			(primitives
				(gr_poly
					(pts
						(arc
							(start 0.1016 0.254)
							(mid 0 0.3556)
							(end -0.1016 0.254)
						)
						(xy -0.1016 -0.3556) (xy 0.1016 -0.3556)
					)
					(width 0)
					(fill yes)
				)
			)
		)
	)
)
